G04 ================== begin FILE IDENTIFICATION RECORD ==================*
G04 Layout Name:  9051_F0T_Panel_BD_Front_D_v02_20221209_1310.brd*
G04 Film Name:    outline*
G04 File Format:  Gerber RS274X*
G04 File Origin:  Cadence Allegro 17.2-S081*
G04 Origin Date:  Mon Dec 12 15:51:17 2022*
G04 *
G04 Layer:  BOARD GEOMETRY/DESIGN_OUTLINE*
G04 Layer:  BOARD GEOMETRY/CUTOUT*
G04 *
G04 Offset:    (0.00 0.00)*
G04 Mirror:    No*
G04 Mode:      Positive*
G04 Rotation:  0*
G04 FullContactRelief:  No*
G04 UndefLineWidth:     6.00*
G04 ================== end FILE IDENTIFICATION RECORD ====================*
%FSLAX25Y25*MOIN*%
%IR0*IPPOS*OFA0.00000B0.00000*MIA0B0*SFA1.00000B1.00000*%
%ADD10C,.006*%
G75*
%LPD*%
G75*
G54D10*
G01X150394Y283264D02*
Y307087D01*
G03X142520Y314961I-7874J0D01*
G01X129331D01*
G02X121457Y322835I0J7874D01*
G01Y331299D01*
G03X113583Y339173I-7874J0D01*
G01X58465D01*
G03X50591Y331299I0J-7874D01*
G01Y322835D01*
G02X42717Y314961I-7874J0D01*
G01X12205D01*
G03X4331Y307087I0J-7874D01*
G01Y283264D01*
G02X2165Y277840I-7875J0D01*
G03X0Y272417I5709J-5423D01*
G01Y7874D01*
G03X7874Y0I7874J0D01*
G01X146850D01*
G03X154724Y7874I0J7874D01*
G01Y272417D01*
G03X152559Y277840I-7874J0D01*
G02X150394Y283264I5710J5423D01*
G01X24016Y50787D02*
G02Y66535I0J7874D01*
G02Y50787I0J-7874D01*
G01X33640Y287042D02*
G03X31890Y282093I6124J-4949D01*
G01Y279449D01*
G02X20079I-5905J0D01*
G01Y282093D01*
G03X18329Y287042I-7874J0D01*
G02X33640I7656J6187D01*
G01X129134Y239669D02*
G02Y255417I0J7874D01*
G02Y239669I0J-7874D01*
G01X143876Y51018D02*
G03X142126Y46069I6124J-4949D01*
G01Y43425D01*
G02X130315I-5906J0D01*
G01Y46069D01*
G03X128565Y51018I-7874J0D01*
G02X143876I7655J6187D01*
M02*
